# S9S_MB_2U (Grand Teton) — schematic netlist excerpt (pin names and nets, part order shuffled) for the footprints in the layout excerpt that follows; sources: Cadence DE-HDL packaged netlist, KiCad conversion of 03242023_DA0F0TMBIJ0_F0T_Motherboard_J_brd_V01_OCP.brd

J18  SCONN288_ADR50017P087CC  SCONN288_ADR50017-P087CC IO  pkg DDR288S_1-1VXB  page 99
  VIN_BULK0  = P12V_S3_AUX_CPU1_NVDIMM
  RFU0  = TP_CHA_CPU1_DIMM2_FRU_0
  VIN_MGMT  = P3V3_AUX
  HSCL  = I3C_SPD_DDRABCD_CPU1_LVC1_SCL_1
  HSDA  = I3C_SPD_DDRABCD_CPU1_LVC1_SDA
  VSS0  = GND
  DQ0_A  = M_A_CPU1_SA_DQ<0>
  VSS1  = GND
  DQ1_A  = M_A_CPU1_SA_DQ<1>
  VSS2  = GND
  DQS0_A_T  = M_A_CPU1_SA_DQS_DP<0>
  DQS0_A_C  = M_A_CPU1_SA_DQS_DN<0>
  VSS3  = GND
  DQ4_A  = M_A_CPU1_SA_DQ<4>
  VSS4  = GND
  DQ5_A  = M_A_CPU1_SA_DQ<5>
  VSS5  = GND
  DQ8_A  = M_A_CPU1_SA_DQ<8>
  VSS6  = GND
  DQ9_A  = M_A_CPU1_SA_DQ<9>
  VSS7  = GND
  DQS1_A_T  = M_A_CPU1_SA_DQS_DP<1>
  DQS1_A_C  = M_A_CPU1_SA_DQS_DN<1>
  VSS8  = GND
  DQ12_A  = M_A_CPU1_SA_DQ<12>
  VSS9  = GND
  DQ13_A  = M_A_CPU1_SA_DQ<13>
  VSS10  = GND
  DQ16_A  = M_A_CPU1_SA_DQ<16>
  VSS11  = GND
  DQ17_A  = M_A_CPU1_SA_DQ<17>
  VSS12  = GND
  DQS2_A_T  = M_A_CPU1_SA_DQS_DP<2>
  DQS2_A_C  = M_A_CPU1_SA_DQS_DN<2>
  VSS13  = GND
  DQ20_A  = M_A_CPU1_SA_DQ<20>
  VSS14  = GND
  DQ21_A  = M_A_CPU1_SA_DQ<21>
  VSS15  = GND
  DQ24_A  = M_A_CPU1_SA_DQ<24>
  VSS16  = GND
  DQ25_A  = M_A_CPU1_SA_DQ<25>
  VSS17  = GND
  DQS3_A_T  = M_A_CPU1_SA_DQS_DP<3>
  DQS3_A_C  = M_A_CPU1_SA_DQS_DN<3>
  VSS18  = GND
  DQ28_A  = M_A_CPU1_SA_DQ<28>
  VSS19  = GND
  DQ29_A  = M_A_CPU1_SA_DQ<29>
  VSS20  = GND
  CB0_A  = M_A_CPU1_SA_CB<0>
  VSS21  = GND
  CB1_A  = M_A_CPU1_SA_CB<1>
  VSS22  = GND
  DQS4_A_T  = M_A_CPU1_SA_DQS_DP<4>
  DQS4_A_C  = M_A_CPU1_SA_DQS_DN<4>
  VSS23  = GND
  CB4_A  = M_A_CPU1_SA_CB<4>
  VSS24  = GND
  CB5_A  = M_A_CPU1_SA_CB<5>
  VSS25  = GND
  ALERT_N  = M_A_CPU1_ALERT_N
  VSS26  = GND
  CS0_A_N  = M_A_CPU1_SA_CS_N<2>
  VSS27  = GND
  CA0_A  = M_A_CPU1_SA_CA<0>
  VSS28  = GND
  CA2_A  = M_A_CPU1_SA_CA<2>
  VSS29  = GND
  CA4_A  = M_A_CPU1_SA_CA<4>
  VSS30  = GND
  CA6_A  = M_A_CPU1_SA_CA<6>
  VSS31  = GND
  PAR_A  = M_A_CPU1_SA_PAR
  VSS32  = GND
  CA0_B  = M_A_CPU1_SB_CA<0>
  VSS33  = GND
  CA2_B  = M_A_CPU1_SB_CA<2>
  VSS34  = GND
  CA4_B  = M_A_CPU1_SB_CA<4>
  VSS35  = GND
  CA6_B  = M_A_CPU1_SB_CA<6>
  VSS36  = GND
  CS0_B_N  = M_A_CPU1_SB_CS_N<2>
  VSS37  = GND
  \lbd||rsp_a_n\  = M_A_CPU1_SA_RSP<1>
  \lbs||rsp_b_n\  = M_A_CPU1_SB_RSP<1>
  VSS38  = GND
  CB4_B  = M_A_CPU1_SB_CB<4>
  VSS39  = GND
  CB5_B  = M_A_CPU1_SB_CB<5>
  VSS40  = GND
  \dqs9_b_t||tdqs9_b_t||dbi4_b_n\  = M_A_CPU1_SB_DQS_DP<9>
  \dqs9_b_c||tdqs9_b_c\  = M_A_CPU1_SB_DQS_DN<9>
  VSS41  = GND
  CB0_B  = M_A_CPU1_SB_CB<0>
  VSS42  = GND
  CB1_B  = M_A_CPU1_SB_CB<1>
  VSS43  = GND
  DQ0_B  = M_A_CPU1_SB_DQ<0>
  VSS44  = GND
  DQ1_B  = M_A_CPU1_SB_DQ<1>
  VSS45  = GND
  DQS0_B_T  = M_A_CPU1_SB_DQS_DP<0>
  DQS0_B_C  = M_A_CPU1_SB_DQS_DN<0>
  VSS46  = GND
  DQ4_B  = M_A_CPU1_SB_DQ<4>
  VSS47  = GND
  DQ5_B  = M_A_CPU1_SB_DQ<5>
  VSS48  = GND
  DQ8_B  = M_A_CPU1_SB_DQ<8>
  VSS49  = GND
  DQ9_B  = M_A_CPU1_SB_DQ<9>
  VSS50  = GND
  DQS1_B_T  = M_A_CPU1_SB_DQS_DP<1>
  DQS1_B_C  = M_A_CPU1_SB_DQS_DN<1>
  VSS51  = GND
  DQ12_B  = M_A_CPU1_SB_DQ<12>
  VSS52  = GND
  DQ13_B  = M_A_CPU1_SB_DQ<13>
  VSS53  = GND
  DQ16_B  = M_A_CPU1_SB_DQ<16>
  VSS54  = GND
  DQ17_B  = M_A_CPU1_SB_DQ<17>
  VSS55  = GND
  DQS2_B_T  = M_A_CPU1_SB_DQS_DP<2>
  DQS2_B_C  = M_A_CPU1_SB_DQS_DN<2>
  VSS56  = GND
  DQ20_B  = M_A_CPU1_SB_DQ<20>
  VSS57  = GND
  DQ21_B  = M_A_CPU1_SB_DQ<21>
  VSS58  = GND
  DQ24_B  = M_A_CPU1_SB_DQ<24>
  VSS59  = GND
  DQ25_B  = M_A_CPU1_SB_DQ<25>
  VSS60  = GND
  DQS3_B_T  = M_A_CPU1_SB_DQS_DP<3>
  DQS3_B_C  = M_A_CPU1_SB_DQS_DN<3>
  VSS61  = GND
  DQ28_B  = M_A_CPU1_SB_DQ<28>
  VSS62  = GND
  DQ29_B  = M_A_CPU1_SB_DQ<29>
  VSS63  = GND
  RFU1  = TP_CHA_CPU1_DIMM2_FRU_1
  VIN_BULK1  = P12V_S3_AUX_CPU1_NVDIMM
  VIN_BULK2  = P12V_S3_AUX_CPU1_NVDIMM
  \pwr_good||fail_n\  = PWRGD_CHA_CPU1_DIMM2
  HSA  = PD_CHA_CPU1_DIMM2_SAA
  RFU2  = TP_CHA_CPU1_DIMM2_FRU_2
  RFU3  = TP_CHA_CPU1_DIMM2_FRU_3
  VSS64  = GND
  DQ2_A  = M_A_CPU1_SA_DQ<2>
  VSS65  = GND
  DQ3_A  = M_A_CPU1_SA_DQ<3>
  VSS66  = GND
  \dqs5_a_c||tdqs5_a_c||dqs5_a_t||tdqs5_a_t\  = M_A_CPU1_SA_DQS_DN<5>
  \dqs5_a_t||tdqs5_a_t\  = M_A_CPU1_SA_DQS_DP<5>
  VSS67  = GND
  DQ6_A  = M_A_CPU1_SA_DQ<6>
  VSS68  = GND
  DQ7_A  = M_A_CPU1_SA_DQ<7>
  VSS69  = GND
  DQ10_A  = M_A_CPU1_SA_DQ<10>
  VSS70  = GND
  DQ11_A  = M_A_CPU1_SA_DQ<11>
  VSS71  = GND
  \dqs6_a_c||tdqs6_a_c||dqs6_a_t||tdqs6_a_t\  = M_A_CPU1_SA_DQS_DN<6>
  \dqs6_a_t||tdqs6_a_t\  = M_A_CPU1_SA_DQS_DP<6>
  VSS72  = GND
  DQ14_A  = M_A_CPU1_SA_DQ<14>
  VSS73  = GND
  DQ15_A  = M_A_CPU1_SA_DQ<15>
  VSS74  = GND
  DQ18_A  = M_A_CPU1_SA_DQ<18>
  VSS75  = GND
  DQ19_A  = M_A_CPU1_SA_DQ<19>
  VSS76  = GND
  \dqs7_a_c||tdqs7_a_c\  = M_A_CPU1_SA_DQS_DN<7>
  \dqs7_a_t||tdqs7_a_t\  = M_A_CPU1_SA_DQS_DP<7>
  VSS77  = GND
  DQ22_A  = M_A_CPU1_SA_DQ<22>
  VSS78  = GND
  DQ23_A  = M_A_CPU1_SA_DQ<23>
  VSS79  = GND
  DQ26_A  = M_A_CPU1_SA_DQ<26>
  VSS80  = GND
  DQ27_A  = M_A_CPU1_SA_DQ<27>
  VSS81  = GND
  \dqs8_a_c||tdqs8_a_c\  = M_A_CPU1_SA_DQS_DN<8>
  \dqs8_a_t||tdqs8_a_t\  = M_A_CPU1_SA_DQS_DP<8>
  VSS82  = GND
  DQ30_A  = M_A_CPU1_SA_DQ<30>
  VSS83  = GND
  DQ31_A  = M_A_CPU1_SA_DQ<31>
  VSS84  = GND
  CB2_A  = M_A_CPU1_SA_CB<2>
  VSS85  = GND
  CB3_A  = M_A_CPU1_SA_CB<3>
  VSS86  = GND
  \dqs9_a_c||tdqs9_a_c\  = M_A_CPU1_SA_DQS_DN<9>
  \dqs9_a_t||tdqs9_a_t\  = M_A_CPU1_SA_DQS_DP<9>
  VSS87  = GND
  CB6_A  = M_A_CPU1_SA_CB<6>
  VSS88  = GND
  CB7_A  = M_A_CPU1_SA_CB<7>
  VSS89  = GND
  RESET_N  = RST_M_AB_CPU1_FPGA_N
  VSS90  = GND
  CS1_A_N  = M_A_CPU1_SA_CS_N<3>
  VSS91  = GND
  CA1_A  = M_A_CPU1_SA_CA<1>
  VSS92  = GND
  CA3_A  = M_A_CPU1_SA_CA<3>
  VSS93  = GND
  CA5_A  = M_A_CPU1_SA_CA<5>
  VSS94  = GND
  CK_T  = M_A_CPU1_CLK_DP<1>
  CK_C  = M_A_CPU1_CLK_DN<1>
  VSS95  = GND
  RFU4  = TP_CHA_CPU1_DIMM2_FRU_4
  CA1_B  = M_A_CPU1_SB_CA<1>
  VSS96  = GND
  CA3_B  = M_A_CPU1_SB_CA<3>
  VSS97  = GND
  CA5_B  = M_A_CPU1_SB_CA<5>
  VSS98  = GND
  PAR_B  = M_A_CPU1_SB_PAR
  VSS99  = GND
  CS1_B_N  = M_A_CPU1_SB_CS_N<3>
  VSS100  = GND
  RFU5  = TP_CHA_CPU1_DIMM2_FRU_5
  RFU6  = TP_CHA_CPU1_DIMM2_FRU_6
  VSS101  = GND
  CB6_B  = M_A_CPU1_SB_CB<6>
  VSS102  = GND
  CB7_B  = M_A_CPU1_SB_CB<7>
  VSS103  = GND
  DQS4_B_C  = M_A_CPU1_SB_DQS_DN<4>
  DQS4_B_T  = M_A_CPU1_SB_DQS_DP<4>
  VSS104  = GND
  CB2_B  = M_A_CPU1_SB_CB<2>
  VSS105  = GND
  CB3_B  = M_A_CPU1_SB_CB<3>
  VSS106  = GND
  DQ2_B  = M_A_CPU1_SB_DQ<2>
  VSS107  = GND
  DQ3_B  = M_A_CPU1_SB_DQ<3>
  VSS108  = GND
  \dqs5_b_c||tdqs5_b_c\  = M_A_CPU1_SB_DQS_DN<5>
  \dqs5_b_t||tdqs5_b_t\  = M_A_CPU1_SB_DQS_DP<5>
  VSS109  = GND
  DQ6_B  = M_A_CPU1_SB_DQ<6>
  VSS110  = GND
  DQ7_B  = M_A_CPU1_SB_DQ<7>
  VSS111  = GND
  DQ10_B  = M_A_CPU1_SB_DQ<10>
  VSS112  = GND
  DQ11_B  = M_A_CPU1_SB_DQ<11>
  VSS113  = GND
  \dqs6_b_c||tdqs6_b_c\  = M_A_CPU1_SB_DQS_DN<6>
  \dqs6_b_t||tdqs6_b_t\  = M_A_CPU1_SB_DQS_DP<6>
  VSS114  = GND
  DQ14_B  = M_A_CPU1_SB_DQ<14>
  VSS115  = GND
  DQ15_B  = M_A_CPU1_SB_DQ<15>
  VSS116  = GND
  DQ18_B  = M_A_CPU1_SB_DQ<18>
  VSS117  = GND
  DQ19_B  = M_A_CPU1_SB_DQ<19>
  VSS118  = GND
  \dqs7_b_c||tdqs7_b_c\  = M_A_CPU1_SB_DQS_DN<7>
  \dqs7_b_t||tdqs7_b_t\  = M_A_CPU1_SB_DQS_DP<7>
  VSS119  = GND
  DQ22_B  = M_A_CPU1_SB_DQ<22>
  VSS120  = GND
  DQ23_B  = M_A_CPU1_SB_DQ<23>
  VSS121  = GND
  DQ26_B  = M_A_CPU1_SB_DQ<26>
  VSS122  = GND
  DQ27_B  = M_A_CPU1_SB_DQ<27>
  VSS123  = GND
  \dqs8_b_c||tdqs8_b_c\  = M_A_CPU1_SB_DQS_DN<8>
  \dqs8_b_t||tdqs8_b_t\  = M_A_CPU1_SB_DQS_DP<8>
  VSS124  = GND
  DQ30_B  = M_A_CPU1_SB_DQ<30>
  VSS125  = GND
  DQ31_B  = M_A_CPU1_SB_DQ<31>
  VSS126  = GND
  G1  = GND
  G2  = GND
  G3  = GND

(kicad_pcb
	(version 20260206)
	(generator "pcbnew")
	(generator_version "10.0")
	(general
		(thickness 1.6)
		(legacy_teardrops no)
	)
	(paper "A4")
	(title_block
		(title "03242023_DA0F0TMBIJ0_F0T_Motherboard_J_brd_V01_OCP.brd")
		(comment 1 "Grand Teton / footprint 3819 of 6105 (J18), pads 92-137 of 291")
	)
	(layers
		(0 "F.Cu" signal "TOP")
		(4 "In1.Cu" signal "GND")
		(6 "In2.Cu" signal "IN1")
		(8 "In3.Cu" signal "GND1")
		(10 "In4.Cu" signal "IN2")
		(12 "In5.Cu" signal "GND2")
		(14 "In6.Cu" signal "IN3")
		(16 "In7.Cu" signal "GND3")
		(18 "In8.Cu" signal "VCC")
		(20 "In9.Cu" signal "VCC1")
		(22 "In10.Cu" signal "GND4")
		(24 "In11.Cu" signal "IN4")
		(26 "In12.Cu" signal "GND5")
		(28 "In13.Cu" signal "IN5")
		(30 "In14.Cu" signal "GND6")
		(32 "In15.Cu" signal "IN6")
		(34 "In16.Cu" signal "GND7")
		(2 "B.Cu" signal "BOTTOM")
		(9 "F.Adhes" user "F.Adhesive")
		(11 "B.Adhes" user "B.Adhesive")
		(13 "F.Paste" user "Package Geometry/Pastemask Top")
		(15 "B.Paste" user "Package Geometry/Pastemask Bottom")
		(5 "F.SilkS" user "Ref Des/Silkscreen Top")
		(7 "B.SilkS" user "Ref Des/Silkscreen Bottom")
		(1 "F.Mask" user "Board Geometry/Soldermask Top")
		(3 "B.Mask" user "Board Geometry/Soldermask Bottom")
		(17 "Dwgs.User" user "User.Drawings")
		(19 "Cmts.User" user "User.Comments")
		(21 "Eco1.User" user "User.Eco1")
		(23 "Eco2.User" user "User.Eco2")
		(25 "Edge.Cuts" user "Board Geometry/Outline")
		(27 "Margin" user)
		(31 "F.CrtYd" user "Package Geometry/Place Bound Top")
		(29 "B.CrtYd" user "Package Geometry/Place Bound Bottom")
		(35 "F.Fab" user "Ref Des/Assembly Top")
		(33 "B.Fab" user "Ref Des/Assembly Bottom")
	)
	(footprint ""
		(layer "F.Cu")
		(at 62.99708 -258.091686)
		(property "Reference" "J18"
			(at -1.547622 -81.836514 0)
			(unlocked yes)
			(layer "F.SilkS")
			(effects
				(font
					(size 0.7874 0.5842)
					(thickness 0.1524)
				)
				(justify left)
			)
		)
		(property "Value" ""
			(at 0 0 0)
			(layer "F.Fab")
			(effects
				(font
					(size 1.27 1.27)
				)
			)
		)
		(duplicate_pad_numbers_are_jumpers no)
		(pad "92" smd rect
			(at -2.050034 19.12493 270)
			(size 0.519938 1.4986)
			(layers "F.Cu" "F.Mask" "F.Paste")
			(net "GND")
		)
		(pad "93" smd rect
			(at -2.050034 19.975068 270)
			(size 0.519938 1.4986)
			(layers "F.Cu" "F.Mask" "F.Paste")
			(net "M_A_CPU1_SB_DQS_DP<9>")
		)
		(pad "94" smd rect
			(at -2.050034 20.824952 270)
			(size 0.519938 1.4986)
			(layers "F.Cu" "F.Mask" "F.Paste")
			(net "M_A_CPU1_SB_DQS_DN<9>")
		)
		(pad "95" smd rect
			(at -2.050034 21.67509 270)
			(size 0.519938 1.4986)
			(layers "F.Cu" "F.Mask" "F.Paste")
			(net "GND")
		)
		(pad "96" smd rect
			(at -2.050034 22.524974 270)
			(size 0.519938 1.4986)
			(layers "F.Cu" "F.Mask" "F.Paste")
			(net "M_A_CPU1_SB_CB<0>")
		)
		(pad "97" smd rect
			(at -2.050034 23.375112 270)
			(size 0.519938 1.4986)
			(layers "F.Cu" "F.Mask" "F.Paste")
			(net "GND")
		)
		(pad "98" smd rect
			(at -2.050034 24.224996 270)
			(size 0.519938 1.4986)
			(layers "F.Cu" "F.Mask" "F.Paste")
			(net "M_A_CPU1_SB_CB<1>")
		)
		(pad "99" smd rect
			(at -2.050034 25.07488 270)
			(size 0.519938 1.4986)
			(layers "F.Cu" "F.Mask" "F.Paste")
			(net "GND")
		)
		(pad "100" smd rect
			(at -2.050034 25.925018 270)
			(size 0.519938 1.4986)
			(layers "F.Cu" "F.Mask" "F.Paste")
			(net "M_A_CPU1_SB_DQ<0>")
		)
		(pad "101" smd rect
			(at -2.050034 26.774902 270)
			(size 0.519938 1.4986)
			(layers "F.Cu" "F.Mask" "F.Paste")
			(net "GND")
		)
		(pad "102" smd rect
			(at -2.050034 27.62504 270)
			(size 0.519938 1.4986)
			(layers "F.Cu" "F.Mask" "F.Paste")
			(net "M_A_CPU1_SB_DQ<1>")
		)
		(pad "103" smd rect
			(at -2.050034 28.474924 270)
			(size 0.519938 1.4986)
			(layers "F.Cu" "F.Mask" "F.Paste")
			(net "GND")
		)
		(pad "104" smd rect
			(at -2.050034 29.325062 270)
			(size 0.519938 1.4986)
			(layers "F.Cu" "F.Mask" "F.Paste")
			(net "M_A_CPU1_SB_DQS_DP<0>")
		)
		(pad "105" smd rect
			(at -2.050034 30.174946 270)
			(size 0.519938 1.4986)
			(layers "F.Cu" "F.Mask" "F.Paste")
			(net "M_A_CPU1_SB_DQS_DN<0>")
		)
		(pad "106" smd rect
			(at -2.050034 31.025084 270)
			(size 0.519938 1.4986)
			(layers "F.Cu" "F.Mask" "F.Paste")
			(net "GND")
		)
		(pad "107" smd rect
			(at -2.050034 31.874968 270)
			(size 0.519938 1.4986)
			(layers "F.Cu" "F.Mask" "F.Paste")
			(net "M_A_CPU1_SB_DQ<4>")
		)
		(pad "108" smd rect
			(at -2.050034 32.725106 270)
			(size 0.519938 1.4986)
			(layers "F.Cu" "F.Mask" "F.Paste")
			(net "GND")
		)
		(pad "109" smd rect
			(at -2.050034 33.57499 270)
			(size 0.519938 1.4986)
			(layers "F.Cu" "F.Mask" "F.Paste")
			(net "M_A_CPU1_SB_DQ<5>")
		)
		(pad "110" smd rect
			(at -2.050034 34.425128 270)
			(size 0.519938 1.4986)
			(layers "F.Cu" "F.Mask" "F.Paste")
			(net "GND")
		)
		(pad "111" smd rect
			(at -2.050034 35.275012 270)
			(size 0.519938 1.4986)
			(layers "F.Cu" "F.Mask" "F.Paste")
			(net "M_A_CPU1_SB_DQ<8>")
		)
		(pad "112" smd rect
			(at -2.050034 36.124896 270)
			(size 0.519938 1.4986)
			(layers "F.Cu" "F.Mask" "F.Paste")
			(net "GND")
		)
		(pad "113" smd rect
			(at -2.050034 36.975034 270)
			(size 0.519938 1.4986)
			(layers "F.Cu" "F.Mask" "F.Paste")
			(net "M_A_CPU1_SB_DQ<9>")
		)
		(pad "114" smd rect
			(at -2.050034 37.824918 270)
			(size 0.519938 1.4986)
			(layers "F.Cu" "F.Mask" "F.Paste")
			(net "GND")
		)
		(pad "115" smd rect
			(at -2.050034 38.675056 270)
			(size 0.519938 1.4986)
			(layers "F.Cu" "F.Mask" "F.Paste")
			(net "M_A_CPU1_SB_DQS_DP<1>")
		)
		(pad "116" smd rect
			(at -2.050034 39.52494 270)
			(size 0.519938 1.4986)
			(layers "F.Cu" "F.Mask" "F.Paste")
			(net "M_A_CPU1_SB_DQS_DN<1>")
		)
		(pad "117" smd rect
			(at -2.050034 40.375078 270)
			(size 0.519938 1.4986)
			(layers "F.Cu" "F.Mask" "F.Paste")
			(net "GND")
		)
		(pad "118" smd rect
			(at -2.050034 41.224962 270)
			(size 0.519938 1.4986)
			(layers "F.Cu" "F.Mask" "F.Paste")
			(net "M_A_CPU1_SB_DQ<12>")
		)
		(pad "119" smd rect
			(at -2.050034 42.0751 270)
			(size 0.519938 1.4986)
			(layers "F.Cu" "F.Mask" "F.Paste")
			(net "GND")
		)
		(pad "120" smd rect
			(at -2.050034 42.924984 270)
			(size 0.519938 1.4986)
			(layers "F.Cu" "F.Mask" "F.Paste")
			(net "M_A_CPU1_SB_DQ<13>")
		)
		(pad "121" smd rect
			(at -2.050034 43.775122 270)
			(size 0.519938 1.4986)
			(layers "F.Cu" "F.Mask" "F.Paste")
			(net "GND")
		)
		(pad "122" smd rect
			(at -2.050034 44.625006 270)
			(size 0.519938 1.4986)
			(layers "F.Cu" "F.Mask" "F.Paste")
			(net "M_A_CPU1_SB_DQ<16>")
		)
		(pad "123" smd rect
			(at -2.050034 45.47489 270)
			(size 0.519938 1.4986)
			(layers "F.Cu" "F.Mask" "F.Paste")
			(net "GND")
		)
		(pad "124" smd rect
			(at -2.050034 46.325028 270)
			(size 0.519938 1.4986)
			(layers "F.Cu" "F.Mask" "F.Paste")
			(net "M_A_CPU1_SB_DQ<17>")
		)
		(pad "125" smd rect
			(at -2.050034 47.174912 270)
			(size 0.519938 1.4986)
			(layers "F.Cu" "F.Mask" "F.Paste")
			(net "GND")
		)
		(pad "126" smd rect
			(at -2.050034 48.02505 270)
			(size 0.519938 1.4986)
			(layers "F.Cu" "F.Mask" "F.Paste")
			(net "M_A_CPU1_SB_DQS_DP<2>")
		)
		(pad "127" smd rect
			(at -2.050034 48.874934 270)
			(size 0.519938 1.4986)
			(layers "F.Cu" "F.Mask" "F.Paste")
			(net "M_A_CPU1_SB_DQS_DN<2>")
		)
		(pad "128" smd rect
			(at -2.050034 49.725072 270)
			(size 0.519938 1.4986)
			(layers "F.Cu" "F.Mask" "F.Paste")
			(net "GND")
		)
		(pad "129" smd rect
			(at -2.050034 50.574956 270)
			(size 0.519938 1.4986)
			(layers "F.Cu" "F.Mask" "F.Paste")
			(net "M_A_CPU1_SB_DQ<20>")
		)
		(pad "130" smd rect
			(at -2.050034 51.425094 270)
			(size 0.519938 1.4986)
			(layers "F.Cu" "F.Mask" "F.Paste")
			(net "GND")
		)
		(pad "131" smd rect
			(at -2.050034 52.274978 270)
			(size 0.519938 1.4986)
			(layers "F.Cu" "F.Mask" "F.Paste")
			(net "M_A_CPU1_SB_DQ<21>")
		)
		(pad "132" smd rect
			(at -2.050034 53.125116 270)
			(size 0.519938 1.4986)
			(layers "F.Cu" "F.Mask" "F.Paste")
			(net "GND")
		)
		(pad "133" smd rect
			(at -2.050034 53.975 270)
			(size 0.519938 1.4986)
			(layers "F.Cu" "F.Mask" "F.Paste")
			(net "M_A_CPU1_SB_DQ<24>")
		)
		(pad "134" smd rect
			(at -2.050034 54.824884 270)
			(size 0.519938 1.4986)
			(layers "F.Cu" "F.Mask" "F.Paste")
			(net "GND")
		)
		(pad "135" smd rect
			(at -2.050034 55.675022 270)
			(size 0.519938 1.4986)
			(layers "F.Cu" "F.Mask" "F.Paste")
			(net "M_A_CPU1_SB_DQ<25>")
		)
		(pad "136" smd rect
			(at -2.050034 56.524906 270)
			(size 0.519938 1.4986)
			(layers "F.Cu" "F.Mask" "F.Paste")
			(net "GND")
		)
		(pad "137" smd rect
			(at -2.050034 57.375044 270)
			(size 0.519938 1.4986)
			(layers "F.Cu" "F.Mask" "F.Paste")
			(net "M_A_CPU1_SB_DQS_DP<3>")
		)
	)
)
